FILE_TYPE = MACRO_DRAWING;
SET COLOR_WIRE YELLOW;
SET COLOR_PROP ORANGE;
SET COLOR_DOT WHITE;
SET COLOR_ARC YELLOW;
SET COLOR_BODY GREEN;
SET COLOR_NOTE PURPLE;
SET PROP_DISPLAY VALUE;
SET PAGE_NUMBER P367;
FORCEADD QUANTA_TITLE_BLOCK_C..1
(0 0);
FORCEPROP 1 LAST CUSTOM_TXT_CDS <NAME_2>
J 0
(-3175 50);
FORCEPROP 1 LAST CUSTOM_TXT_CDS <NAME_1>
J 0
(-3175 175);
FORCEPROP 1 LAST CUSTOM_TXT_CDS <Q_NUMBER>
J 0
(-1403 103);
DISPLAY 1.212766 (-1403 103);
FORCEPROP 1 LAST CUSTOM_TXT_CDS <Q_PROJ>
J 0
(-2382 102);
DISPLAY 1.212766 (-2382 102);
FORCEPROP 1 LAST CUSTOM_TXT_CDS <Q_REV>
J 0
(-184 103);
DISPLAY 1.212766 (-184 103);
FORCEPROP 1 LAST CUSTOM_TXT_CDS <CON_LAST_MODIFIED>
J 0
(-1885 15);
DISPLAY 0.978723 (-1885 15);
FORCEPROP 1 LAST CUSTOM_TXT_CDS <CON_PAGE_NUM> OF <CON_TOTAL_PAGES>
J 0
(-446 18);
DISPLAY 0.978723 (-446 18);
FORCEPROP 1 LAST Q_TITLE Blank
J 0
(-9325 25);
DISPLAY 2.446809 (-9325 25);
PAINT GREEN (-9325 25);
FORCEPROP 1 LAST CDS_LMAN_SYM_OUTLINE -9475,6775,100,-125
J 0
(0 0);
DISPLAY 0.468085 (0 0);
PAINT GREEN (0 0);
DISPLAY INVISIBLE (0 0);
FORCEPROP 2 LAST CDS_LIB pure_quanta
J 0
(0 0);
DISPLAY INVISIBLE (0 0);
FORCEPROP 2 LAST PAGE_BORDER TRUE
J 0
(-7890 5250);
DISPLAY 0.638298 (-7890 5250);
PAINT PINK (-7890 5250);
DISPLAY INVISIBLE (-7890 5250);
FORCEPROP 2 LAST CDS_XR_PAGE_TITLE CR-245 : @T6G_MB_LIB.T6G(SCH_1):PAGE245
J 0
(-7890 5250);
DISPLAY 0.638298 (-7890 5250);
PAINT PINK (-7890 5250);
DISPLAY INVISIBLE (-7890 5250);
FORCEPROP 2 LAST CUSTOM_TXT_CDS <XR_PAGE_TITLE>
J 0
(-7890 5250);
DISPLAY 0.638298 (-7890 5250);
PAINT PINK (-7890 5250);
DISPLAY INVISIBLE (-7890 5250);
FORCEPROP 1 LAST COMMENT_BODY TRUE
J 0
(12 -13);
DISPLAY 0.978723 (12 -13);
PAINT GREEN (12 -13);
DISPLAY INVISIBLE (12 -13);
FORCEPROP 1 LAST Q_DEPT BU9
J 1
(-3763 49);
DISPLAY 1.957447 (-3763 49);
PAINT GREEN (-3763 49);
DISPLAY INVISIBLE (-3763 49);
FORCEPROP 0 LAST CDS_CON_LAST_MODIFIED Thu Aug 24 10:15:41 2023
J 0
(-1885 15);
DISPLAY INVISIBLE (-1885 15);
QUIT
